# T6G (Grand Teton) — schematic netlist excerpt (pin names and nets, part order shuffled) for the footprints in the layout excerpt that follows; sources: Cadence DE-HDL packaged netlist, KiCad conversion of 04192023_DAF0TMB3IC0_F0TG_MB_C_brd_V02_OCP.brd

R830  Q_RES  0 5% CHIP  pkg 0201LF  page 185 : A = SMB_RT_CPU0_P3_ROM_MUX_2D_R_SDA ; B = SMB_RT_CPU0_P3_ROM_MUX_2D_SDA
R88  Q_RES  1K 1% EMPTY  pkg 0402LF  page 86 : A = P3V3 ; B = PWRGD_CHAF_CPU0
C2074  Q_CAP_DIFFBUS  DIFF BUS_0.22UF 6.3V 20% X6S  pkg C0201  page 53 : \1\ = P3E_CPU1_P5_TX_C_DN<1> ; \2\ = P3E_CPU1_P5_TX_DN<1>

(kicad_pcb
	(version 20260206)
	(generator "pcbnew")
	(generator_version "10.0")
	(general
		(thickness 1.6)
		(legacy_teardrops no)
	)
	(paper "A4")
	(title_block
		(title "04192023_DAF0TMB3IC0_F0TG_MB_C_brd_V02_OCP.brd")
		(comment 1 "Grand Teton / footprints 8035-8037 of 8354")
	)
	(layers
		(0 "F.Cu" signal "TOP")
		(4 "In1.Cu" signal "GND")
		(6 "In2.Cu" signal "IN1")
		(8 "In3.Cu" signal "GND1")
		(10 "In4.Cu" signal "IN2")
		(12 "In5.Cu" signal "GND2")
		(14 "In6.Cu" signal "IN3")
		(16 "In7.Cu" signal "GND3")
		(18 "In8.Cu" signal "VCC")
		(20 "In9.Cu" signal "VCC1")
		(22 "In10.Cu" signal "GND4")
		(24 "In11.Cu" signal "IN4")
		(26 "In12.Cu" signal "GND5")
		(28 "In13.Cu" signal "IN5")
		(30 "In14.Cu" signal "GND6")
		(32 "In15.Cu" signal "IN6")
		(34 "In16.Cu" signal "GND7")
		(2 "B.Cu" signal "BOTTOM")
		(9 "F.Adhes" user "F.Adhesive")
		(11 "B.Adhes" user "B.Adhesive")
		(13 "F.Paste" user "Package Geometry/Pastemask Top")
		(15 "B.Paste" user "Package Geometry/Pastemask Bottom")
		(5 "F.SilkS" user "Ref Des/Silkscreen Top")
		(7 "B.SilkS" user "Ref Des/Silkscreen Bottom")
		(1 "F.Mask" user "Board Geometry/Soldermask Top")
		(3 "B.Mask" user "Board Geometry/Soldermask Bottom")
		(17 "Dwgs.User" user "User.Drawings")
		(19 "Cmts.User" user "User.Comments")
		(21 "Eco1.User" user "User.Eco1")
		(23 "Eco2.User" user "User.Eco2")
		(25 "Edge.Cuts" user "Board Geometry/Outline")
		(27 "Margin" user)
		(31 "F.CrtYd" user "Package Geometry/Place Bound Top")
		(29 "B.CrtYd" user "Package Geometry/Place Bound Bottom")
		(35 "F.Fab" user "Ref Des/Assembly Top")
		(33 "B.Fab" user "Ref Des/Assembly Bottom")
	)
	(footprint ""
		(layer "B.Cu")
		(at 298.526454 -190.82131 180)
		(property "Reference" "R88"
			(at 0 0 0)
			(layer "B.SilkS")
			(hide yes)
			(effects
				(font
					(size 1.27 1.27)
				)
				(justify mirror)
			)
		)
		(property "Value" ""
			(at 0 0 0)
			(layer "B.Fab")
			(effects
				(font
					(size 1.27 1.27)
				)
				(justify mirror)
			)
		)
		(duplicate_pad_numbers_are_jumpers no)
		(fp_line
			(start 0.7874 0.4064)
			(end 0.7874 -0.4064)
			(stroke
				(width 0.1524)
				(type default)
			)
			(layer "B.SilkS")
		)
		(fp_line
			(start 0.7874 -0.4064)
			(end -0.7874 -0.4064)
			(stroke
				(width 0.1524)
				(type default)
			)
			(layer "B.SilkS")
		)
		(fp_line
			(start -0.7874 0.4064)
			(end 0.7874 0.4064)
			(stroke
				(width 0.1524)
				(type default)
			)
			(layer "B.SilkS")
		)
		(fp_line
			(start -0.7874 -0.4064)
			(end -0.7874 0.4064)
			(stroke
				(width 0.1524)
				(type default)
			)
			(layer "B.SilkS")
		)
		(fp_line
			(start 0.67945 0.3048)
			(end 0.67945 -0.305054)
			(stroke
				(width 0.1)
				(type default)
			)
			(layer "B.Fab")
		)
		(fp_line
			(start 0.67945 -0.305054)
			(end 0.12065 -0.305054)
			(stroke
				(width 0.1)
				(type default)
			)
			(layer "B.Fab")
		)
		(fp_line
			(start 0.12065 0.3048)
			(end 0.67945 0.3048)
			(stroke
				(width 0.1)
				(type default)
			)
			(layer "B.Fab")
		)
		(fp_line
			(start 0.12065 0.2794)
			(end 0.12065 0.3048)
			(stroke
				(width 0.1)
				(type default)
			)
			(layer "B.Fab")
		)
		(fp_line
			(start 0.12065 -0.2794)
			(end -0.12065 -0.2794)
			(stroke
				(width 0.1)
				(type default)
			)
			(layer "B.Fab")
		)
		(fp_line
			(start 0.12065 -0.305054)
			(end 0.12065 -0.2794)
			(stroke
				(width 0.1)
				(type default)
			)
			(layer "B.Fab")
		)
		(fp_line
			(start -0.120396 0.3048)
			(end -0.120396 0.2794)
			(stroke
				(width 0.1)
				(type default)
			)
			(layer "B.Fab")
		)
		(fp_line
			(start -0.120396 0.2794)
			(end 0.12065 0.2794)
			(stroke
				(width 0.1)
				(type default)
			)
			(layer "B.Fab")
		)
		(fp_line
			(start -0.12065 -0.2794)
			(end -0.12065 -0.3048)
			(stroke
				(width 0.1)
				(type default)
			)
			(layer "B.Fab")
		)
		(fp_line
			(start -0.12065 -0.3048)
			(end -0.67945 -0.3048)
			(stroke
				(width 0.1)
				(type default)
			)
			(layer "B.Fab")
		)
		(fp_line
			(start -0.67945 0.3048)
			(end -0.120396 0.3048)
			(stroke
				(width 0.1)
				(type default)
			)
			(layer "B.Fab")
		)
		(fp_line
			(start -0.67945 -0.3048)
			(end -0.67945 0.3048)
			(stroke
				(width 0.1)
				(type default)
			)
			(layer "B.Fab")
		)
		(pad "1" smd circle
			(at 0.40005 0)
			(size 0 0)
			(layers "B.Cu" "B.Mask" "B.Paste")
			(net "P3V3")
		)
		(pad "2" smd circle
			(at -0.40005 0)
			(size 0 0)
			(layers "B.Cu" "B.Mask" "B.Paste")
			(net "PWRGD_CHAF_CPU0")
		)
	)
	(footprint ""
		(layer "B.Cu")
		(at 255.905 -337.37804 180)
		(property "Reference" "R830"
			(at 0 0 0)
			(layer "B.SilkS")
			(hide yes)
			(effects
				(font
					(size 1.27 1.27)
				)
				(justify mirror)
			)
		)
		(property "Value" ""
			(at 0 0 0)
			(layer "B.Fab")
			(effects
				(font
					(size 1.27 1.27)
				)
				(justify mirror)
			)
		)
		(duplicate_pad_numbers_are_jumpers no)
		(fp_line
			(start 0.32512 0.175006)
			(end 0.32512 -0.175006)
			(stroke
				(width 0.1)
				(type default)
			)
			(layer "B.Fab")
		)
		(fp_line
			(start 0.32512 -0.175006)
			(end -0.32512 -0.175006)
			(stroke
				(width 0.1)
				(type default)
			)
			(layer "B.Fab")
		)
		(fp_line
			(start -0.32512 0.175006)
			(end 0.32512 0.175006)
			(stroke
				(width 0.1)
				(type default)
			)
			(layer "B.Fab")
		)
		(fp_line
			(start -0.32512 -0.175006)
			(end -0.32512 0.175006)
			(stroke
				(width 0.1)
				(type default)
			)
			(layer "B.Fab")
		)
		(pad "1" smd rect
			(at 0.2667 0)
			(size 0.3048 0.381)
			(layers "B.Cu" "B.Mask" "B.Paste")
			(net "SMB_RT_CPU0_P3_ROM_MUX_2D_R_SDA")
		)
		(pad "2" smd rect
			(at -0.2667 0 180)
			(size 0.3048 0.381)
			(layers "B.Cu" "B.Mask" "B.Paste")
			(net "SMB_RT_CPU0_P3_ROM_MUX_2D_SDA")
		)
	)
	(footprint ""
		(layer "B.Cu")
		(at 44.14901 -412.853378)
		(property "Reference" "C2074"
			(at 0 0 0)
			(layer "B.SilkS")
			(hide yes)
			(effects
				(font
					(size 1.27 1.27)
				)
				(justify mirror)
			)
		)
		(property "Value" ""
			(at 0 0 0)
			(layer "B.Fab")
			(effects
				(font
					(size 1.27 1.27)
				)
				(justify mirror)
			)
		)
		(duplicate_pad_numbers_are_jumpers no)
		(fp_line
			(start -0.299974 -0.150114)
			(end -0.299974 0.150114)
			(stroke
				(width 0.1)
				(type default)
			)
			(layer "B.Fab")
		)
		(fp_line
			(start -0.299974 0.150114)
			(end 0.299974 0.150114)
			(stroke
				(width 0.1)
				(type default)
			)
			(layer "B.Fab")
		)
		(fp_line
			(start 0.299974 -0.150114)
			(end -0.299974 -0.150114)
			(stroke
				(width 0.1)
				(type default)
			)
			(layer "B.Fab")
		)
		(fp_line
			(start 0.299974 0.150114)
			(end 0.299974 -0.150114)
			(stroke
				(width 0.1)
				(type default)
			)
			(layer "B.Fab")
		)
		(pad "1" smd rect
			(at 0.2667 0 180)
			(size 0.3048 0.381)
			(layers "B.Cu" "B.Mask" "B.Paste")
			(net "P3E_CPU1_P5_TX_C_DN<1>")
		)
		(pad "2" smd rect
			(at -0.2667 0 180)
			(size 0.3048 0.381)
			(layers "B.Cu" "B.Mask" "B.Paste")
			(net "P3E_CPU1_P5_TX_DN<1>")
		)
	)
)
